FILE_TYPE=LIBRARY_PARTS;
primitive 'NB3W1200L','NB3W1200L_LCC';
  pin
    'VDDA':
      PIN_NUMBER='(1)';
      PINUSE='POWER';
      NO_LOAD_CHECK='Both';
      NO_IO_CHECK='Both';
      NO_ASSERT_CHECK='TRUE';
      NO_DIR_CHECK='TRUE';
      ALLOW_CONNECT='TRUE';
    'GNDA':
      PIN_NUMBER='(2)';
      PINUSE='GROUND';
      NO_LOAD_CHECK='Both';
      NO_IO_CHECK='Both';
      NO_ASSERT_CHECK='TRUE';
      NO_DIR_CHECK='TRUE';
      ALLOW_CONNECT='TRUE';
    'NC'<0>:
      PIN_NUMBER='(3)';
      PINUSE='NC';
      NO_LOAD_CHECK='Both';
      NO_IO_CHECK='Both';
      ALLOW_CONNECT='TRUE';
    '100M_133M_N':
      PIN_NUMBER='(4)';
      INPUT_LOAD='(-0.01,0.01)';
    'HBW_BYPASS_LOBW_N':
      PIN_NUMBER='(5)';
      INPUT_LOAD='(-0.01,0.01)';
    'PWRGD_PWRDN_N':
      PIN_NUMBER='(6)';
      INPUT_LOAD='(-0.01,0.01)';
    'GND'<0>:
      PIN_NUMBER='(7)';
      PINUSE='GROUND';
      NO_LOAD_CHECK='Both';
      NO_IO_CHECK='Both';
      NO_ASSERT_CHECK='TRUE';
      NO_DIR_CHECK='TRUE';
      ALLOW_CONNECT='TRUE';
    'VDDR':
      PIN_NUMBER='(8)';
      PINUSE='POWER';
      NO_LOAD_CHECK='Both';
      NO_IO_CHECK='Both';
      NO_ASSERT_CHECK='TRUE';
      NO_DIR_CHECK='TRUE';
      ALLOW_CONNECT='TRUE';
    'CLK_INP':
      PIN_NUMBER='(9)';
      INPUT_LOAD='(-0.01,0.01)';
    'CLK_INN':
      PIN_NUMBER='(10)';
      INPUT_LOAD='(-0.01,0.01)';
    'SA_0':
      PIN_NUMBER='(11)';
      INPUT_LOAD='(-0.01,0.01)';
    'SDA':
      PIN_NUMBER='(12)';
      BIDIRECTIONAL='TRUE';
      INPUT_LOAD='(-0.01,0.01)';
      OUTPUT_LOAD='(1.0,-1.0)';
    'SCL':
      PIN_NUMBER='(13)';
      BIDIRECTIONAL='TRUE';
      INPUT_LOAD='(-0.01,0.01)';
      OUTPUT_LOAD='(1.0,-1.0)';
    'SA_1':
      PIN_NUMBER='(14)';
      INPUT_LOAD='(-0.01,0.01)';
    'NC'<2>:
      PIN_NUMBER='(15)';
      PINUSE='NC';
      NO_LOAD_CHECK='Both';
      NO_IO_CHECK='Both';
      ALLOW_CONNECT='TRUE';
    'NC'<1>:
      PIN_NUMBER='(16)';
      PINUSE='NC';
      NO_LOAD_CHECK='Both';
      NO_IO_CHECK='Both';
      ALLOW_CONNECT='TRUE';
    'DIF_0P':
      PIN_NUMBER='(17)';
      OUTPUT_LOAD='(1.0,-1.0)';
    'DIF_0N':
      PIN_NUMBER='(18)';
      OUTPUT_LOAD='(1.0,-1.0)';
    'OE_0_N':
      PIN_NUMBER='(19)';
      INPUT_LOAD='(-0.01,0.01)';
    'OE_1_N':
      PIN_NUMBER='(20)';
      INPUT_LOAD='(-0.01,0.01)';
    'DIF_1P':
      PIN_NUMBER='(21)';
      OUTPUT_LOAD='(1.0,-1.0)';
    'DIF_1N':
      PIN_NUMBER='(22)';
      OUTPUT_LOAD='(1.0,-1.0)';
    'GND'<1>:
      PIN_NUMBER='(23)';
      PINUSE='GROUND';
      NO_LOAD_CHECK='Both';
      NO_IO_CHECK='Both';
      NO_ASSERT_CHECK='TRUE';
      NO_DIR_CHECK='TRUE';
      ALLOW_CONNECT='TRUE';
    'VDD'<0>:
      PIN_NUMBER='(24)';
      PINUSE='POWER';
      NO_LOAD_CHECK='Both';
      NO_IO_CHECK='Both';
      NO_ASSERT_CHECK='TRUE';
      NO_DIR_CHECK='TRUE';
      ALLOW_CONNECT='TRUE';
    'VDDIO'<0>:
      PIN_NUMBER='(25)';
      PINUSE='POWER';
      NO_LOAD_CHECK='Both';
      NO_IO_CHECK='Both';
      NO_ASSERT_CHECK='TRUE';
      NO_DIR_CHECK='TRUE';
      ALLOW_CONNECT='TRUE';
    'DIF_2P':
      PIN_NUMBER='(26)';
      OUTPUT_LOAD='(1.0,-1.0)';
    'DIF_2N':
      PIN_NUMBER='(27)';
      OUTPUT_LOAD='(1.0,-1.0)';
    'OE_2_N':
      PIN_NUMBER='(28)';
      INPUT_LOAD='(-0.01,0.01)';
    'OE_3_N':
      PIN_NUMBER='(29)';
      INPUT_LOAD='(-0.01,0.01)';
    'DIF_3P':
      PIN_NUMBER='(30)';
      OUTPUT_LOAD='(1.0,-1.0)';
    'DIF_3N':
      PIN_NUMBER='(31)';
      OUTPUT_LOAD='(1.0,-1.0)';
    'VDDIO'<1>:
      PIN_NUMBER='(32)';
      PINUSE='POWER';
      NO_LOAD_CHECK='Both';
      NO_IO_CHECK='Both';
      NO_ASSERT_CHECK='TRUE';
      NO_DIR_CHECK='TRUE';
      ALLOW_CONNECT='TRUE';
    'GND'<2>:
      PIN_NUMBER='(33)';
      PINUSE='GROUND';
      NO_LOAD_CHECK='Both';
      NO_IO_CHECK='Both';
      NO_ASSERT_CHECK='TRUE';
      NO_DIR_CHECK='TRUE';
      ALLOW_CONNECT='TRUE';
    'DIF_4P':
      PIN_NUMBER='(34)';
      OUTPUT_LOAD='(1.0,-1.0)';
    'DIF_4N':
      PIN_NUMBER='(35)';
      OUTPUT_LOAD='(1.0,-1.0)';
    'OE_4_N':
      PIN_NUMBER='(36)';
      INPUT_LOAD='(-0.01,0.01)';
    'OE_5_N':
      PIN_NUMBER='(37)';
      INPUT_LOAD='(-0.01,0.01)';
    'DIF_5P':
      PIN_NUMBER='(38)';
      OUTPUT_LOAD='(1.0,-1.0)';
    'DIF_5N':
      PIN_NUMBER='(39)';
      OUTPUT_LOAD='(1.0,-1.0)';
    'VDD'<1>:
      PIN_NUMBER='(40)';
      PINUSE='POWER';
      NO_LOAD_CHECK='Both';
      NO_IO_CHECK='Both';
      NO_ASSERT_CHECK='TRUE';
      NO_DIR_CHECK='TRUE';
      ALLOW_CONNECT='TRUE';
    'GND'<3>:
      PIN_NUMBER='(41)';
      PINUSE='GROUND';
      NO_LOAD_CHECK='Both';
      NO_IO_CHECK='Both';
      NO_ASSERT_CHECK='TRUE';
      NO_DIR_CHECK='TRUE';
      ALLOW_CONNECT='TRUE';
    'DIF_6P':
      PIN_NUMBER='(42)';
      OUTPUT_LOAD='(1.0,-1.0)';
    'DIF_6N':
      PIN_NUMBER='(43)';
      OUTPUT_LOAD='(1.0,-1.0)';
    'OE_6_N':
      PIN_NUMBER='(44)';
      INPUT_LOAD='(-0.01,0.01)';
    'OE_7_N':
      PIN_NUMBER='(45)';
      INPUT_LOAD='(-0.01,0.01)';
    'DIF_7P':
      PIN_NUMBER='(46)';
      OUTPUT_LOAD='(1.0,-1.0)';
    'DIF_7N':
      PIN_NUMBER='(47)';
      OUTPUT_LOAD='(1.0,-1.0)';
    'GND'<4>:
      PIN_NUMBER='(48)';
      PINUSE='GROUND';
      NO_LOAD_CHECK='Both';
      NO_IO_CHECK='Both';
      NO_ASSERT_CHECK='TRUE';
      NO_DIR_CHECK='TRUE';
      ALLOW_CONNECT='TRUE';
    'VDDIO'<2>:
      PIN_NUMBER='(49)';
      PINUSE='POWER';
      NO_LOAD_CHECK='Both';
      NO_IO_CHECK='Both';
      NO_ASSERT_CHECK='TRUE';
      NO_DIR_CHECK='TRUE';
      ALLOW_CONNECT='TRUE';
    'DIF_8P':
      PIN_NUMBER='(50)';
      OUTPUT_LOAD='(1.0,-1.0)';
    'DIF_8N':
      PIN_NUMBER='(51)';
      OUTPUT_LOAD='(1.0,-1.0)';
    'OE_8_N':
      PIN_NUMBER='(52)';
      INPUT_LOAD='(-0.01,0.01)';
    'OE_9_N':
      PIN_NUMBER='(53)';
      INPUT_LOAD='(-0.01,0.01)';
    'DIF_9P':
      PIN_NUMBER='(54)';
      OUTPUT_LOAD='(1.0,-1.0)';
    'DIF_9N':
      PIN_NUMBER='(55)';
      OUTPUT_LOAD='(1.0,-1.0)';
    'VDDIO'<3>:
      PIN_NUMBER='(56)';
      PINUSE='POWER';
      NO_LOAD_CHECK='Both';
      NO_IO_CHECK='Both';
      NO_ASSERT_CHECK='TRUE';
      NO_DIR_CHECK='TRUE';
      ALLOW_CONNECT='TRUE';
    'VDD'<2>:
      PIN_NUMBER='(57)';
      PINUSE='POWER';
      NO_LOAD_CHECK='Both';
      NO_IO_CHECK='Both';
      NO_ASSERT_CHECK='TRUE';
      NO_DIR_CHECK='TRUE';
      ALLOW_CONNECT='TRUE';
    'GND'<5>:
      PIN_NUMBER='(58)';
      PINUSE='GROUND';
      NO_LOAD_CHECK='Both';
      NO_IO_CHECK='Both';
      NO_ASSERT_CHECK='TRUE';
      NO_DIR_CHECK='TRUE';
      ALLOW_CONNECT='TRUE';
    'DIF_10P':
      PIN_NUMBER='(59)';
      OUTPUT_LOAD='(1.0,-1.0)';
    'DIF_10N':
      PIN_NUMBER='(60)';
      OUTPUT_LOAD='(1.0,-1.0)';
    'OE_10_N':
      PIN_NUMBER='(61)';
      INPUT_LOAD='(-0.01,0.01)';
    'OE_11_N':
      PIN_NUMBER='(62)';
      INPUT_LOAD='(-0.01,0.01)';
    'DIF_11P':
      PIN_NUMBER='(63)';
      OUTPUT_LOAD='(1.0,-1.0)';
    'DIF_11N':
      PIN_NUMBER='(64)';
      OUTPUT_LOAD='(1.0,-1.0)';
    'THPAD':
      PIN_NUMBER='(65)';
      PINUSE='GROUND';
      NO_LOAD_CHECK='Both';
      NO_IO_CHECK='Both';
      NO_ASSERT_CHECK='TRUE';
      NO_DIR_CHECK='TRUE';
      ALLOW_CONNECT='TRUE';
  end_pin;
  body
    PART_NAME='NB3W1200L';
    BODY_NAME='NB3W1200L';
    PHYS_DES_PREFIX='EU';
  end_body;
end_primitive;

END.
